FILE_TYPE = CONNECTIVITY;
{Allegro Design Entry HDL 17.2-2016 S081 (4005846) 1/11/2022}
"PAGE_NUMBER" = 34;
0"NC";
1"UPI_CPU0_CPU1_P2P2_DP<23:0>";
2"UPI_CPU0_CPU1_P2P2_DN<23:0>";
3"UPI_CPU1_CPU0_P2P2_DP<23:0>";
4"UPI_CPU1_CPU0_P2P2_DN<23:0>";
5"UPI_CPU1_CPU0_P2P2_DP<0>";
6"UPI_CPU1_CPU0_P2P2_DN<1>";
7"UPI_CPU1_CPU0_P2P2_DP<2>";
8"UPI_CPU1_CPU0_P2P2_DP<3>";
9"UPI_CPU1_CPU0_P2P2_DP<4>";
10"UPI_CPU1_CPU0_P2P2_DN<5>";
11"UPI_CPU1_CPU0_P2P2_DN<6>";
12"UPI_CPU1_CPU0_P2P2_DP<7>";
13"UPI_CPU1_CPU0_P2P2_DP<8>";
14"UPI_CPU1_CPU0_P2P2_DN<9>";
15"UPI_CPU1_CPU0_P2P2_DN<10>";
16"UPI_CPU1_CPU0_P2P2_DP<11>";
17"UPI_CPU1_CPU0_P2P2_DP<12>";
18"UPI_CPU1_CPU0_P2P2_DN<13>";
19"UPI_CPU1_CPU0_P2P2_DP<14>";
20"UPI_CPU1_CPU0_P2P2_DP<15>";
21"UPI_CPU1_CPU0_P2P2_DP<16>";
22"UPI_CPU1_CPU0_P2P2_DN<17>";
23"UPI_CPU1_CPU0_P2P2_DN<18>";
24"UPI_CPU1_CPU0_P2P2_DN<19>";
25"UPI_CPU1_CPU0_P2P2_DN<20>";
26"UPI_CPU1_CPU0_P2P2_DN<21>"$PNN"UPI_CPU1_CPU0_P2P2_DP<21>";
27"UPI_CPU1_CPU0_P2P2_DP<22>";
28"UPI_CPU1_CPU0_P2P2_DN<23>";
29"UPI_CPU1_CPU0_P2P2_DN<0>";
30"UPI_CPU1_CPU0_P2P2_DP<1>";
31"UPI_CPU1_CPU0_P2P2_DN<2>";
32"UPI_CPU1_CPU0_P2P2_DN<3>";
33"UPI_CPU1_CPU0_P2P2_DN<4>";
34"UPI_CPU1_CPU0_P2P2_DP<5>";
35"UPI_CPU1_CPU0_P2P2_DP<6>";
36"UPI_CPU1_CPU0_P2P2_DN<7>";
37"UPI_CPU1_CPU0_P2P2_DN<8>";
38"UPI_CPU1_CPU0_P2P2_DP<9>";
39"UPI_CPU1_CPU0_P2P2_DP<10>";
40"UPI_CPU1_CPU0_P2P2_DN<11>";
41"UPI_CPU1_CPU0_P2P2_DN<12>";
42"UPI_CPU1_CPU0_P2P2_DP<13>";
43"UPI_CPU1_CPU0_P2P2_DN<14>";
44"UPI_CPU1_CPU0_P2P2_DN<15>";
45"UPI_CPU1_CPU0_P2P2_DN<16>";
46"UPI_CPU1_CPU0_P2P2_DP<17>";
47"UPI_CPU1_CPU0_P2P2_DP<18>";
48"UPI_CPU1_CPU0_P2P2_DP<19>";
49"UPI_CPU1_CPU0_P2P2_DP<20>";
50"UPI_CPU1_CPU0_P2P2_DP<21>";
51"UPI_CPU1_CPU0_P2P2_DN<22>";
52"UPI_CPU1_CPU0_P2P2_DP<23>";
53"UPI_CPU0_CPU1_P2P2_DN<0>";
54"UPI_CPU0_CPU1_P2P2_DN<1>";
55"UPI_CPU0_CPU1_P2P2_DN<2>";
56"UPI_CPU0_CPU1_P2P2_DN<3>";
57"UPI_CPU0_CPU1_P2P2_DN<4>";
58"UPI_CPU0_CPU1_P2P2_DN<5>";
59"UPI_CPU0_CPU1_P2P2_DN<6>";
60"UPI_CPU0_CPU1_P2P2_DN<7>";
61"UPI_CPU0_CPU1_P2P2_DN<8>";
62"UPI_CPU0_CPU1_P2P2_DN<9>";
63"UPI_CPU0_CPU1_P2P2_DN<10>";
64"UPI_CPU0_CPU1_P2P2_DN<11>";
65"UPI_CPU0_CPU1_P2P2_DN<12>";
66"UPI_CPU0_CPU1_P2P2_DN<13>";
67"UPI_CPU0_CPU1_P2P2_DN<14>";
68"UPI_CPU0_CPU1_P2P2_DN<15>";
69"UPI_CPU0_CPU1_P2P2_DN<16>";
70"UPI_CPU0_CPU1_P2P2_DN<17>";
71"UPI_CPU0_CPU1_P2P2_DN<18>";
72"UPI_CPU0_CPU1_P2P2_DN<19>";
73"UPI_CPU0_CPU1_P2P2_DN<20>";
74"UPI_CPU0_CPU1_P2P2_DN<21>";
75"UPI_CPU0_CPU1_P2P2_DN<22>";
76"UPI_CPU0_CPU1_P2P2_DN<23>";
77"UPI_CPU0_CPU1_P2P2_DP<0>";
78"UPI_CPU0_CPU1_P2P2_DP<1>";
79"UPI_CPU0_CPU1_P2P2_DP<2>";
80"UPI_CPU0_CPU1_P2P2_DP<3>";
81"UPI_CPU0_CPU1_P2P2_DP<4>";
82"UPI_CPU0_CPU1_P2P2_DP<5>";
83"UPI_CPU0_CPU1_P2P2_DP<6>";
84"UPI_CPU0_CPU1_P2P2_DP<7>";
85"UPI_CPU0_CPU1_P2P2_DP<8>";
86"UPI_CPU0_CPU1_P2P2_DP<9>";
87"UPI_CPU0_CPU1_P2P2_DP<10>";
88"UPI_CPU0_CPU1_P2P2_DP<11>";
89"UPI_CPU0_CPU1_P2P2_DP<12>";
90"UPI_CPU0_CPU1_P2P2_DP<13>";
91"UPI_CPU0_CPU1_P2P2_DP<14>";
92"UPI_CPU0_CPU1_P2P2_DP<15>";
93"UPI_CPU0_CPU1_P2P2_DP<16>";
94"UPI_CPU0_CPU1_P2P2_DP<17>";
95"UPI_CPU0_CPU1_P2P2_DP<18>";
96"UPI_CPU0_CPU1_P2P2_DP<19>";
97"UPI_CPU0_CPU1_P2P2_DP<20>";
98"UPI_CPU0_CPU1_P2P2_DP<21>";
99"UPI_CPU0_CPU1_P2P2_DP<22>";
100"UPI_CPU0_CPU1_P2P2_DP<23>";
%"SOCKET4677_AZIF0045P001C01CS"
"24","(900,2600)","0","pure_quanta","I102";
;
PART_NUMBER"DGA^7000023"
VALUE"SOCKET4677_AZIF0045-P001C01CS"
MATERIAL"IO"
PART_TYPE"SMLF"
$LOCATION"U2"
CDS_LMAN_SYM_OUTLINE"-1050,1350,1050,-1350"
NEEDS_NO_SIZE"TRUE"
CDS_LIB"pure_quanta"
CDS_LOCATION"U2"
$SEC"24"
CDS_SEC"24";
"UPI2_TX_DP0"
$PN"D85"100;
"UPI2_TX_DP1"
$PN"F85"99;
"UPI2_TX_DP2"
$PN"E88"98;
"UPI2_TX_DP3"
$PN"H87"97;
"UPI2_TX_DP4"
$PN"G86"96;
"UPI2_TX_DP5"
$PN"T81"95;
"UPI2_TX_DP6"
$PN"P83"94;
"UPI2_TX_DP7"
$PN"V81"93;
"UPI2_TX_DP8"
$PN"Y83"92;
"UPI2_TX_DP9"
$PN"W82"91;
"UPI2_TX_DP10"
$PN"BA78"90;
"UPI2_TX_DP11"
$PN"AV79"89;
"UPI2_TX_DP12"
$PN"AP81"88;
"UPI2_TX_DP13"
$PN"AM83"87;
"UPI2_TX_DP14"
$PN"AT81"86;
"UPI2_TX_DP15"
$PN"AV83"85;
"UPI2_TX_DP16"
$PN"AU82"84;
"UPI2_TX_DP17"
$PN"BB81"83;
"UPI2_TX_DP18"
$PN"BA82"82;
"UPI2_TX_DP19"
$PN"BD83"81;
"UPI2_TX_DP20"
$PN"BC80"80;
"UPI2_TX_DP21"
$PN"BG82"79;
"UPI2_TX_DP22"
$PN"BE80"78;
"UPI2_TX_DP23"
$PN"BN72"77;
"UPI2_TX_DN0"
$PN"B85"76;
"UPI2_TX_DN1"
$PN"E84"75;
"UPI2_TX_DN2"
$PN"D87"74;
"UPI2_TX_DN3"
$PN"F87"73;
"UPI2_TX_DN4"
$PN"H85"72;
"UPI2_TX_DN5"
$PN"P81"71;
"UPI2_TX_DN6"
$PN"R82"70;
"UPI2_TX_DN7"
$PN"U80"69;
"UPI2_TX_DN8"
$PN"V83"68;
"UPI2_TX_DN9"
$PN"Y81"67;
"UPI2_TX_DN10"
$PN"AW78"66;
"UPI2_TX_DN11"
$PN"AU78"65;
"UPI2_TX_DN12"
$PN"AM81"64;
"UPI2_TX_DN13"
$PN"AN82"63;
"UPI2_TX_DN14"
$PN"AR80"62;
"UPI2_TX_DN15"
$PN"AT83"61;
"UPI2_TX_DN16"
$PN"AV81"60;
"UPI2_TX_DN17"
$PN"BA80"59;
"UPI2_TX_DN18"
$PN"BC82"58;
"UPI2_TX_DN19"
$PN"BE82"57;
"UPI2_TX_DN20"
$PN"BD79"56;
"UPI2_TX_DN21"
$PN"BF81"55;
"UPI2_TX_DN22"
$PN"BG80"54;
"UPI2_TX_DN23"
$PN"BM71"53;
"UPI2_RX_DP0"
$PN"G80"52;
"UPI2_RX_DP1"
$PN"E82"51;
"UPI2_RX_DP2"
$PN"H83"50;
"UPI2_RX_DP3"
$PN"M79"49;
"UPI2_RX_DP4"
$PN"L82"48;
"UPI2_RX_DP5"
$PN"K81"47;
"UPI2_RX_DP6"
$PN"AE80"46;
"UPI2_RX_DP7"
$PN"AC82"45;
"UPI2_RX_DP8"
$PN"AG80"44;
"UPI2_RX_DP9"
$PN"AF83"43;
"UPI2_RX_DP10"
$PN"AH81"42;
"UPI2_RX_DP11"
$PN"AJ82"41;
"UPI2_RX_DP12"
$PN"BB73"40;
"UPI2_RX_DP13"
$PN"AY73"39;
"UPI2_RX_DP14"
$PN"BA76"38;
"UPI2_RX_DP15"
$PN"BD75"37;
"UPI2_RX_DP16"
$PN"AV75"36;
"UPI2_RX_DP17"
$PN"BG76"35;
"UPI2_RX_DP18"
$PN"BK77"34;
"UPI2_RX_DP19"
$PN"BN76"33;
"UPI2_RX_DP20"
$PN"BJ74"32;
"UPI2_RX_DP21"
$PN"BM75"31;
"UPI2_RX_DP22"
$PN"BL74"30;
"UPI2_RX_DP23"
$PN"BC74"29;
"UPI2_RX_DN0"
$PN"E80"28;
"UPI2_RX_DN1"
$PN"F81"27;
"UPI2_RX_DN2"
$PN"G82"26;
"UPI2_RX_DN3"
$PN"K79"25;
"UPI2_RX_DN4"
$PN"J82"24;
"UPI2_RX_DN5"
$PN"L80"23;
"UPI2_RX_DN6"
$PN"AC80"22;
"UPI2_RX_DN7"
$PN"AD81"21;
"UPI2_RX_DN8"
$PN"AF79"20;
"UPI2_RX_DN9"
$PN"AE82"19;
"UPI2_RX_DN10"
$PN"AJ80"18;
"UPI2_RX_DN11"
$PN"AG82"17;
"UPI2_RX_DN12"
$PN"BA72"16;
"UPI2_RX_DN13"
$PN"AV73"15;
"UPI2_RX_DN14"
$PN"AY75"14;
"UPI2_RX_DN15"
$PN"BB75"13;
"UPI2_RX_DN16"
$PN"AW74"12;
"UPI2_RX_DN17"
$PN"BH75"11;
"UPI2_RX_DN18"
$PN"BJ76"10;
"UPI2_RX_DN19"
$PN"BL76"9;
"UPI2_RX_DN20"
$PN"BG74"8;
"UPI2_RX_DN21"
$PN"BN74"7;
"UPI2_RX_DN22"
$PN"BK73"6;
"UPI2_RX_DN23"
$PN"BD73"5;
%"TAP"
"1","(-1000,2700)","2","standard","I103";
;
CDS_LIB"standard"
BODY_TYPE"PLUMBING"
HDL_TAP"TRUE";
"B \NAC \NWC"4;
"S \NAC"
BN"22"51;
%"TAP"
"1","(-1000,3000)","2","standard","I105";
;
CDS_LIB"standard"
BODY_TYPE"PLUMBING"
HDL_TAP"TRUE";
"B \NAC \NWC"4;
"S \NAC"
BN"16"45;
%"TAP"
"1","(-1000,3250)","2","standard","I106";
;
CDS_LIB"standard"
BODY_TYPE"PLUMBING"
HDL_TAP"TRUE";
"B \NAC \NWC"4;
"S \NAC"
BN"11"40;
%"TAP"
"1","(-1000,3200)","2","standard","I107";
;
CDS_LIB"standard"
BODY_TYPE"PLUMBING"
HDL_TAP"TRUE";
"B \NAC \NWC"4;
"S \NAC"
BN"12"41;
%"TAP"
"1","(-1000,3050)","2","standard","I108";
;
CDS_LIB"standard"
BODY_TYPE"PLUMBING"
HDL_TAP"TRUE";
"B \NAC \NWC"4;
"S \NAC"
BN"15"44;
%"TAP"
"1","(-1000,3100)","2","standard","I109";
;
CDS_LIB"standard"
BODY_TYPE"PLUMBING"
HDL_TAP"TRUE";
"B \NAC \NWC"4;
"S \NAC"
BN"14"43;
%"TAP"
"1","(-1000,3400)","2","standard","I110";
;
CDS_LIB"standard"
BODY_TYPE"PLUMBING"
HDL_TAP"TRUE";
"B \NAC \NWC"4;
"S \NAC"
BN"8"37;
%"TAP"
"1","(-1000,3450)","2","standard","I111";
;
CDS_LIB"standard"
BODY_TYPE"PLUMBING"
HDL_TAP"TRUE";
"B \NAC \NWC"4;
"S \NAC"
BN"7"36;
%"TAP"
"1","(-1000,3600)","2","standard","I112";
;
CDS_LIB"standard"
BODY_TYPE"PLUMBING"
HDL_TAP"TRUE";
"B \NAC \NWC"4;
"S \NAC"
BN"4"33;
%"TAP"
"1","(-1000,3650)","2","standard","I113";
;
CDS_LIB"standard"
BODY_TYPE"PLUMBING"
HDL_TAP"TRUE";
"B \NAC \NWC"4;
"S \NAC"
BN"3"32;
%"TAP"
"1","(-1000,3700)","2","standard","I114";
;
CDS_LIB"standard"
BODY_TYPE"PLUMBING"
HDL_TAP"TRUE";
"B \NAC \NWC"4;
"S \NAC"
BN"2"31;
%"TAP"
"1","(-1000,3800)","2","standard","I115";
;
CDS_LIB"standard"
BODY_TYPE"PLUMBING"
HDL_TAP"TRUE";
"B \NAC \NWC"4;
"S \NAC"
BN"0"29;
%"TAP"
"1","(-800,1450)","2","standard","I116";
;
CDS_LIB"standard"
BODY_TYPE"PLUMBING"
HDL_TAP"TRUE";
"B \NAC \NWC"3;
"S \NAC"
BN"22"27;
%"TAP"
"1","(-800,1750)","2","standard","I118";
;
CDS_LIB"standard"
BODY_TYPE"PLUMBING"
HDL_TAP"TRUE";
"B \NAC \NWC"3;
"S \NAC"
BN"16"21;
%"TAP"
"1","(-800,2000)","2","standard","I119";
;
CDS_LIB"standard"
BODY_TYPE"PLUMBING"
HDL_TAP"TRUE";
"B \NAC \NWC"3;
"S \NAC"
BN"11"16;
%"TAP"
"1","(-800,1950)","2","standard","I120";
;
CDS_LIB"standard"
BODY_TYPE"PLUMBING"
HDL_TAP"TRUE";
"B \NAC \NWC"3;
"S \NAC"
BN"12"17;
%"TAP"
"1","(-800,1800)","2","standard","I121";
;
CDS_LIB"standard"
BODY_TYPE"PLUMBING"
HDL_TAP"TRUE";
"B \NAC \NWC"3;
"S \NAC"
BN"15"20;
%"TAP"
"1","(-800,1850)","2","standard","I122";
;
CDS_LIB"standard"
BODY_TYPE"PLUMBING"
HDL_TAP"TRUE";
"B \NAC \NWC"3;
"S \NAC"
BN"14"19;
%"TAP"
"1","(-800,2150)","2","standard","I123";
;
CDS_LIB"standard"
BODY_TYPE"PLUMBING"
HDL_TAP"TRUE";
"B \NAC \NWC"3;
"S \NAC"
BN"8"13;
%"TAP"
"1","(-800,2200)","2","standard","I124";
;
CDS_LIB"standard"
BODY_TYPE"PLUMBING"
HDL_TAP"TRUE";
"B \NAC \NWC"3;
"S \NAC"
BN"7"12;
%"TAP"
"1","(-800,2350)","2","standard","I125";
;
CDS_LIB"standard"
BODY_TYPE"PLUMBING"
HDL_TAP"TRUE";
"B \NAC \NWC"3;
"S \NAC"
BN"4"9;
%"TAP"
"1","(-800,2400)","2","standard","I126";
;
CDS_LIB"standard"
BODY_TYPE"PLUMBING"
HDL_TAP"TRUE";
"B \NAC \NWC"3;
"S \NAC"
BN"3"8;
%"TAP"
"1","(-800,2450)","2","standard","I127";
;
CDS_LIB"standard"
BODY_TYPE"PLUMBING"
HDL_TAP"TRUE";
"B \NAC \NWC"3;
"S \NAC"
BN"2"7;
%"TAP"
"1","(-800,2550)","2","standard","I128";
;
CDS_LIB"standard"
BODY_TYPE"PLUMBING"
HDL_TAP"TRUE";
"B \NAC \NWC"3;
"S \NAC"
BN"0"5;
%"TAP"
"1","(-1000,1500)","2","standard","I130";
;
CDS_LIB"standard"
BODY_TYPE"PLUMBING"
HDL_TAP"TRUE";
"B \NAC \NWC"4;
"S \NAC"
BN"21"26;
%"TAP"
"1","(-800,2750)","2","standard","I131";
;
CDS_LIB"standard"
BODY_TYPE"PLUMBING"
HDL_TAP"TRUE";
"B \NAC \NWC"3;
"S \NAC"
BN"21"50;
%"TAP"
"1","(-1000,1900)","2","standard","I14";
;
CDS_LIB"standard"
BODY_TYPE"PLUMBING"
HDL_TAP"TRUE";
"B \NAC \NWC"4;
"S \NAC"
BN"13"18;
%"TAP"
"1","(-1000,2050)","2","standard","I16";
;
CDS_LIB"standard"
BODY_TYPE"PLUMBING"
HDL_TAP"TRUE";
"B \NAC \NWC"4;
"S \NAC"
BN"10"15;
%"TAP"
"1","(-1000,2100)","2","standard","I17";
;
CDS_LIB"standard"
BODY_TYPE"PLUMBING"
HDL_TAP"TRUE";
"B \NAC \NWC"4;
"S \NAC"
BN"9"14;
%"TAP"
"1","(-1000,2250)","2","standard","I20";
;
CDS_LIB"standard"
BODY_TYPE"PLUMBING"
HDL_TAP"TRUE";
"B \NAC \NWC"4;
"S \NAC"
BN"6"11;
%"TAP"
"1","(-1000,2300)","2","standard","I22";
;
CDS_LIB"standard"
BODY_TYPE"PLUMBING"
HDL_TAP"TRUE";
"B \NAC \NWC"4;
"S \NAC"
BN"5"10;
%"TAP"
"1","(-1000,2500)","2","standard","I26";
;
CDS_LIB"standard"
BODY_TYPE"PLUMBING"
HDL_TAP"TRUE";
"B \NAC \NWC"4;
"S \NAC"
BN"1"6;
%"TAP"
"1","(-800,2650)","2","standard","I28";
;
CDS_LIB"standard"
BODY_TYPE"PLUMBING"
HDL_TAP"TRUE";
"B \NAC \NWC"3;
"S \NAC"
BN"23"52;
%"TAP"
"1","(-800,2800)","2","standard","I31";
;
CDS_LIB"standard"
BODY_TYPE"PLUMBING"
HDL_TAP"TRUE";
"B \NAC \NWC"3;
"S \NAC"
BN"20"49;
%"TAP"
"1","(-800,2850)","2","standard","I32";
;
CDS_LIB"standard"
BODY_TYPE"PLUMBING"
HDL_TAP"TRUE";
"B \NAC \NWC"3;
"S \NAC"
BN"19"48;
%"TAP"
"1","(-800,2900)","2","standard","I33";
;
CDS_LIB"standard"
BODY_TYPE"PLUMBING"
HDL_TAP"TRUE";
"B \NAC \NWC"3;
"S \NAC"
BN"18"47;
%"TAP"
"1","(-800,2950)","2","standard","I34";
;
CDS_LIB"standard"
BODY_TYPE"PLUMBING"
HDL_TAP"TRUE";
"B \NAC \NWC"3;
"S \NAC"
BN"17"46;
%"TAP"
"1","(-800,3150)","2","standard","I38";
;
CDS_LIB"standard"
BODY_TYPE"PLUMBING"
HDL_TAP"TRUE";
"B \NAC \NWC"3;
"S \NAC"
BN"13"42;
%"TAP"
"1","(-800,3350)","2","standard","I41";
;
CDS_LIB"standard"
BODY_TYPE"PLUMBING"
HDL_TAP"TRUE";
"B \NAC \NWC"3;
"S \NAC"
BN"9"38;
%"TAP"
"1","(-800,3300)","2","standard","I42";
;
CDS_LIB"standard"
BODY_TYPE"PLUMBING"
HDL_TAP"TRUE";
"B \NAC \NWC"3;
"S \NAC"
BN"10"39;
%"TAP"
"1","(-800,3550)","2","standard","I45";
;
CDS_LIB"standard"
BODY_TYPE"PLUMBING"
HDL_TAP"TRUE";
"B \NAC \NWC"3;
"S \NAC"
BN"5"34;
%"TAP"
"1","(-800,3500)","2","standard","I46";
;
CDS_LIB"standard"
BODY_TYPE"PLUMBING"
HDL_TAP"TRUE";
"B \NAC \NWC"3;
"S \NAC"
BN"6"35;
%"TAP"
"1","(-1000,1400)","2","standard","I5";
;
CDS_LIB"standard"
BODY_TYPE"PLUMBING"
HDL_TAP"TRUE";
"B \NAC \NWC"4;
"S \NAC"
BN"23"28;
%"TAP"
"1","(-800,3750)","2","standard","I50";
;
CDS_LIB"standard"
BODY_TYPE"PLUMBING"
HDL_TAP"TRUE";
"B \NAC \NWC"3;
"S \NAC"
BN"1"30;
%"TAP"
"1","(2575,1500)","0","standard","I52";
;
CDS_LIB"standard"
BODY_TYPE"PLUMBING"
HDL_TAP"TRUE";
"B \NAC \NWC"2;
"S \NAC"
BN"21"74;
%"TAP"
"1","(2575,1450)","0","standard","I53";
;
CDS_LIB"standard"
BODY_TYPE"PLUMBING"
HDL_TAP"TRUE";
"B \NAC \NWC"2;
"S \NAC"
BN"22"75;
%"TAP"
"1","(2575,1400)","0","standard","I54";
;
CDS_LIB"standard"
BODY_TYPE"PLUMBING"
HDL_TAP"TRUE";
"B \NAC \NWC"2;
"S \NAC"
BN"23"76;
%"TAP"
"1","(2575,1600)","0","standard","I55";
;
CDS_LIB"standard"
BODY_TYPE"PLUMBING"
HDL_TAP"TRUE";
"B \NAC \NWC"2;
"S \NAC"
BN"19"72;
%"TAP"
"1","(2575,1650)","0","standard","I56";
;
CDS_LIB"standard"
BODY_TYPE"PLUMBING"
HDL_TAP"TRUE";
"B \NAC \NWC"2;
"S \NAC"
BN"18"71;
%"TAP"
"1","(2575,1550)","0","standard","I57";
;
CDS_LIB"standard"
BODY_TYPE"PLUMBING"
HDL_TAP"TRUE";
"B \NAC \NWC"2;
"S \NAC"
BN"20"73;
%"TAP"
"1","(2575,1700)","0","standard","I58";
;
CDS_LIB"standard"
BODY_TYPE"PLUMBING"
HDL_TAP"TRUE";
"B \NAC \NWC"2;
"S \NAC"
BN"17"70;
%"TAP"
"1","(2575,1750)","0","standard","I59";
;
CDS_LIB"standard"
BODY_TYPE"PLUMBING"
HDL_TAP"TRUE";
"B \NAC \NWC"2;
"S \NAC"
BN"16"69;
%"TAP"
"1","(-1000,1550)","2","standard","I6";
;
CDS_LIB"standard"
BODY_TYPE"PLUMBING"
HDL_TAP"TRUE";
"B \NAC \NWC"4;
"S \NAC"
BN"20"25;
%"TAP"
"1","(2575,1800)","0","standard","I60";
;
CDS_LIB"standard"
BODY_TYPE"PLUMBING"
HDL_TAP"TRUE";
"B \NAC \NWC"2;
"S \NAC"
BN"15"68;
%"TAP"
"1","(2575,1900)","0","standard","I61";
;
CDS_LIB"standard"
BODY_TYPE"PLUMBING"
HDL_TAP"TRUE";
"B \NAC \NWC"2;
"S \NAC"
BN"13"66;
%"TAP"
"1","(2575,1850)","0","standard","I62";
;
CDS_LIB"standard"
BODY_TYPE"PLUMBING"
HDL_TAP"TRUE";
"B \NAC \NWC"2;
"S \NAC"
BN"14"67;
%"TAP"
"1","(2575,2000)","0","standard","I63";
;
CDS_LIB"standard"
BODY_TYPE"PLUMBING"
HDL_TAP"TRUE";
"B \NAC \NWC"2;
"S \NAC"
BN"11"64;
%"TAP"
"1","(2575,1950)","0","standard","I64";
;
CDS_LIB"standard"
BODY_TYPE"PLUMBING"
HDL_TAP"TRUE";
"B \NAC \NWC"2;
"S \NAC"
BN"12"65;
%"TAP"
"1","(2575,2050)","0","standard","I65";
;
CDS_LIB"standard"
BODY_TYPE"PLUMBING"
HDL_TAP"TRUE";
"B \NAC \NWC"2;
"S \NAC"
BN"10"63;
%"TAP"
"1","(2575,2150)","0","standard","I66";
;
CDS_LIB"standard"
BODY_TYPE"PLUMBING"
HDL_TAP"TRUE";
"B \NAC \NWC"2;
"S \NAC"
BN"8"61;
%"TAP"
"1","(2575,2100)","0","standard","I67";
;
CDS_LIB"standard"
BODY_TYPE"PLUMBING"
HDL_TAP"TRUE";
"B \NAC \NWC"2;
"S \NAC"
BN"9"62;
%"TAP"
"1","(2575,2250)","0","standard","I68";
;
CDS_LIB"standard"
BODY_TYPE"PLUMBING"
HDL_TAP"TRUE";
"B \NAC \NWC"2;
"S \NAC"
BN"6"59;
%"TAP"
"1","(2575,2200)","0","standard","I69";
;
CDS_LIB"standard"
BODY_TYPE"PLUMBING"
HDL_TAP"TRUE";
"B \NAC \NWC"2;
"S \NAC"
BN"7"60;
%"TAP"
"1","(-1000,1600)","2","standard","I7";
;
CDS_LIB"standard"
BODY_TYPE"PLUMBING"
HDL_TAP"TRUE";
"B \NAC \NWC"4;
"S \NAC"
BN"19"24;
%"TAP"
"1","(2575,2350)","0","standard","I70";
;
CDS_LIB"standard"
BODY_TYPE"PLUMBING"
HDL_TAP"TRUE";
"B \NAC \NWC"2;
"S \NAC"
BN"4"57;
%"TAP"
"1","(2575,2300)","0","standard","I71";
;
CDS_LIB"standard"
BODY_TYPE"PLUMBING"
HDL_TAP"TRUE";
"B \NAC \NWC"2;
"S \NAC"
BN"5"58;
%"TAP"
"1","(2575,2400)","0","standard","I72";
;
CDS_LIB"standard"
BODY_TYPE"PLUMBING"
HDL_TAP"TRUE";
"B \NAC \NWC"2;
"S \NAC"
BN"3"56;
%"TAP"
"1","(2575,2450)","0","standard","I73";
;
CDS_LIB"standard"
BODY_TYPE"PLUMBING"
HDL_TAP"TRUE";
"B \NAC \NWC"2;
"S \NAC"
BN"2"55;
%"TAP"
"1","(2575,2500)","0","standard","I74";
;
CDS_LIB"standard"
BODY_TYPE"PLUMBING"
HDL_TAP"TRUE";
"B \NAC \NWC"2;
"S \NAC"
BN"1"54;
%"TAP"
"1","(2575,2750)","0","standard","I75";
;
CDS_LIB"standard"
BODY_TYPE"PLUMBING"
HDL_TAP"TRUE";
"B \NAC \NWC"1;
"S \NAC"
BN"21"98;
%"TAP"
"1","(2575,2650)","0","standard","I76";
;
CDS_LIB"standard"
BODY_TYPE"PLUMBING"
HDL_TAP"TRUE";
"B \NAC \NWC"1;
"S \NAC"
BN"23"100;
%"TAP"
"1","(2575,2550)","0","standard","I77";
;
CDS_LIB"standard"
BODY_TYPE"PLUMBING"
HDL_TAP"TRUE";
"B \NAC \NWC"2;
"S \NAC"
BN"0"53;
%"TAP"
"1","(2575,2700)","0","standard","I78";
;
CDS_LIB"standard"
BODY_TYPE"PLUMBING"
HDL_TAP"TRUE";
"B \NAC \NWC"1;
"S \NAC"
BN"22"99;
%"TAP"
"1","(2575,2800)","0","standard","I79";
;
CDS_LIB"standard"
BODY_TYPE"PLUMBING"
HDL_TAP"TRUE";
"B \NAC \NWC"1;
"S \NAC"
BN"20"97;
%"TAP"
"1","(-1000,1650)","2","standard","I8";
;
CDS_LIB"standard"
BODY_TYPE"PLUMBING"
HDL_TAP"TRUE";
"B \NAC \NWC"4;
"S \NAC"
BN"18"23;
%"TAP"
"1","(2575,2900)","0","standard","I80";
;
CDS_LIB"standard"
BODY_TYPE"PLUMBING"
HDL_TAP"TRUE";
"B \NAC \NWC"1;
"S \NAC"
BN"18"95;
%"TAP"
"1","(2575,2850)","0","standard","I81";
;
CDS_LIB"standard"
BODY_TYPE"PLUMBING"
HDL_TAP"TRUE";
"B \NAC \NWC"1;
"S \NAC"
BN"19"96;
%"TAP"
"1","(2575,3000)","0","standard","I82";
;
CDS_LIB"standard"
BODY_TYPE"PLUMBING"
HDL_TAP"TRUE";
"B \NAC \NWC"1;
"S \NAC"
BN"16"93;
%"TAP"
"1","(2575,2950)","0","standard","I83";
;
CDS_LIB"standard"
BODY_TYPE"PLUMBING"
HDL_TAP"TRUE";
"B \NAC \NWC"1;
"S \NAC"
BN"17"94;
%"TAP"
"1","(2575,3150)","0","standard","I84";
;
CDS_LIB"standard"
BODY_TYPE"PLUMBING"
HDL_TAP"TRUE";
"B \NAC \NWC"1;
"S \NAC"
BN"13"90;
%"TAP"
"1","(2575,3100)","0","standard","I85";
;
CDS_LIB"standard"
BODY_TYPE"PLUMBING"
HDL_TAP"TRUE";
"B \NAC \NWC"1;
"S \NAC"
BN"14"91;
%"TAP"
"1","(2575,3050)","0","standard","I86";
;
CDS_LIB"standard"
BODY_TYPE"PLUMBING"
HDL_TAP"TRUE";
"B \NAC \NWC"1;
"S \NAC"
BN"15"92;
%"TAP"
"1","(2575,3200)","0","standard","I87";
;
CDS_LIB"standard"
BODY_TYPE"PLUMBING"
HDL_TAP"TRUE";
"B \NAC \NWC"1;
"S \NAC"
BN"12"89;
%"TAP"
"1","(2575,3250)","0","standard","I88";
;
CDS_LIB"standard"
BODY_TYPE"PLUMBING"
HDL_TAP"TRUE";
"B \NAC \NWC"1;
"S \NAC"
BN"11"88;
%"TAP"
"1","(2575,3500)","0","standard","I89";
;
CDS_LIB"standard"
BODY_TYPE"PLUMBING"
HDL_TAP"TRUE";
"B \NAC \NWC"1;
"S \NAC"
BN"6"83;
%"TAP"
"1","(-1000,1700)","2","standard","I9";
;
CDS_LIB"standard"
BODY_TYPE"PLUMBING"
HDL_TAP"TRUE";
"B \NAC \NWC"4;
"S \NAC"
BN"17"22;
%"TAP"
"1","(2575,3550)","0","standard","I90";
;
CDS_LIB"standard"
BODY_TYPE"PLUMBING"
HDL_TAP"TRUE";
"B \NAC \NWC"1;
"S \NAC"
BN"5"82;
%"TAP"
"1","(2575,3450)","0","standard","I91";
;
CDS_LIB"standard"
BODY_TYPE"PLUMBING"
HDL_TAP"TRUE";
"B \NAC \NWC"1;
"S \NAC"
BN"7"84;
%"TAP"
"1","(2575,3350)","0","standard","I92";
;
CDS_LIB"standard"
BODY_TYPE"PLUMBING"
HDL_TAP"TRUE";
"B \NAC \NWC"1;
"S \NAC"
BN"9"86;
%"TAP"
"1","(2575,3300)","0","standard","I93";
;
CDS_LIB"standard"
BODY_TYPE"PLUMBING"
HDL_TAP"TRUE";
"B \NAC \NWC"1;
"S \NAC"
BN"10"87;
%"TAP"
"1","(2575,3400)","0","standard","I94";
;
CDS_LIB"standard"
BODY_TYPE"PLUMBING"
HDL_TAP"TRUE";
"B \NAC \NWC"1;
"S \NAC"
BN"8"85;
%"TAP"
"1","(2575,3600)","0","standard","I95";
;
CDS_LIB"standard"
BODY_TYPE"PLUMBING"
HDL_TAP"TRUE";
"B \NAC \NWC"1;
"S \NAC"
BN"4"81;
%"TAP"
"1","(2575,3650)","0","standard","I96";
;
CDS_LIB"standard"
BODY_TYPE"PLUMBING"
HDL_TAP"TRUE";
"B \NAC \NWC"1;
"S \NAC"
BN"3"80;
%"TAP"
"1","(2575,3700)","0","standard","I97";
;
CDS_LIB"standard"
BODY_TYPE"PLUMBING"
HDL_TAP"TRUE";
"B \NAC \NWC"1;
"S \NAC"
BN"2"79;
%"TAP"
"1","(2575,3800)","0","standard","I98";
;
CDS_LIB"standard"
BODY_TYPE"PLUMBING"
HDL_TAP"TRUE";
"B \NAC \NWC"1;
"S \NAC"
BN"0"77;
%"TAP"
"1","(2575,3750)","0","standard","I99";
;
CDS_LIB"standard"
BODY_TYPE"PLUMBING"
HDL_TAP"TRUE";
"B \NAC \NWC"1;
"S \NAC"
BN"1"78;
END.
